(kicad_pcb
	(version 20260206)
	(generator "pcbnew")
	(generator_version "10.0")
	(general
		(thickness 1.6)
		(legacy_teardrops no)
	)
	(paper "A4")
	(title_block
		(title "12092022_DA0F0TFB6D0_F0T_FAN_BOARD_MP5048_D_brd_v02_OCP.brd")
		(comment 1 "Grand Teton / footprints 357-362 of 924")
	)
	(layers
		(0 "F.Cu" signal "TOP")
		(4 "In1.Cu" signal "GND")
		(6 "In2.Cu" signal "IN1")
		(8 "In3.Cu" signal "IN2")
		(10 "In4.Cu" signal "GND1")
		(2 "B.Cu" signal "BOTTOM")
		(9 "F.Adhes" user "F.Adhesive")
		(11 "B.Adhes" user "B.Adhesive")
		(13 "F.Paste" user "Package Geometry/Pastemask Top")
		(15 "B.Paste" user "Package Geometry/Pastemask Bottom")
		(5 "F.SilkS" user "Ref Des/Silkscreen Top")
		(7 "B.SilkS" user "Ref Des/Silkscreen Bottom")
		(1 "F.Mask" user "Board Geometry/Soldermask Top")
		(3 "B.Mask" user "Board Geometry/Soldermask Bottom")
		(17 "Dwgs.User" user "User.Drawings")
		(19 "Cmts.User" user "User.Comments")
		(21 "Eco1.User" user "User.Eco1")
		(23 "Eco2.User" user "User.Eco2")
		(25 "Edge.Cuts" user "Board Geometry/Outline")
		(27 "Margin" user)
		(31 "F.CrtYd" user "Package Geometry/Place Bound Top")
		(29 "B.CrtYd" user "Package Geometry/Place Bound Bottom")
		(35 "F.Fab" user "Ref Des/Assembly Top")
		(33 "B.Fab" user "Ref Des/Assembly Bottom")
	)
	(footprint ""
		(layer "F.Cu")
		(at 48.26 -135.128 180)
		(property "Reference" "R5557"
			(at 0 0 180)
			(layer "F.SilkS")
			(hide yes)
			(effects
				(font
					(size 1.27 1.27)
				)
			)
		)
		(property "Value" ""
			(at 0 0 180)
			(layer "F.Fab")
			(effects
				(font
					(size 1.27 1.27)
				)
			)
		)
		(duplicate_pad_numbers_are_jumpers no)
		(fp_line
			(start 0.7874 0.4064)
			(end -0.7874 0.4064)
			(stroke
				(width 0.1524)
				(type default)
			)
			(layer "F.SilkS")
		)
		(fp_line
			(start 0.7874 -0.4064)
			(end 0.7874 0.4064)
			(stroke
				(width 0.1524)
				(type default)
			)
			(layer "F.SilkS")
		)
		(fp_line
			(start -0.7874 0.4064)
			(end -0.7874 -0.4064)
			(stroke
				(width 0.1524)
				(type default)
			)
			(layer "F.SilkS")
		)
		(fp_line
			(start -0.7874 -0.4064)
			(end 0.7874 -0.4064)
			(stroke
				(width 0.1524)
				(type default)
			)
			(layer "F.SilkS")
		)
		(fp_line
			(start 0.67945 0.3048)
			(end 0.120396 0.3048)
			(stroke
				(width 0.1)
				(type default)
			)
			(layer "F.Fab")
		)
		(fp_line
			(start 0.67945 -0.3048)
			(end 0.67945 0.3048)
			(stroke
				(width 0.1)
				(type default)
			)
			(layer "F.Fab")
		)
		(fp_line
			(start 0.12065 -0.2794)
			(end 0.12065 -0.3048)
			(stroke
				(width 0.1)
				(type default)
			)
			(layer "F.Fab")
		)
		(fp_line
			(start 0.12065 -0.3048)
			(end 0.67945 -0.3048)
			(stroke
				(width 0.1)
				(type default)
			)
			(layer "F.Fab")
		)
		(fp_line
			(start 0.120396 0.3048)
			(end 0.120396 0.2794)
			(stroke
				(width 0.1)
				(type default)
			)
			(layer "F.Fab")
		)
		(fp_line
			(start 0.120396 0.2794)
			(end -0.12065 0.2794)
			(stroke
				(width 0.1)
				(type default)
			)
			(layer "F.Fab")
		)
		(fp_line
			(start -0.12065 0.3048)
			(end -0.67945 0.3048)
			(stroke
				(width 0.1)
				(type default)
			)
			(layer "F.Fab")
		)
		(fp_line
			(start -0.12065 0.2794)
			(end -0.12065 0.3048)
			(stroke
				(width 0.1)
				(type default)
			)
			(layer "F.Fab")
		)
		(fp_line
			(start -0.12065 -0.2794)
			(end 0.12065 -0.2794)
			(stroke
				(width 0.1)
				(type default)
			)
			(layer "F.Fab")
		)
		(fp_line
			(start -0.12065 -0.305054)
			(end -0.12065 -0.2794)
			(stroke
				(width 0.1)
				(type default)
			)
			(layer "F.Fab")
		)
		(fp_line
			(start -0.67945 0.3048)
			(end -0.67945 -0.305054)
			(stroke
				(width 0.1)
				(type default)
			)
			(layer "F.Fab")
		)
		(fp_line
			(start -0.67945 -0.305054)
			(end -0.12065 -0.305054)
			(stroke
				(width 0.1)
				(type default)
			)
			(layer "F.Fab")
		)
		(pad "1" smd circle
			(at -0.40005 0 180)
			(size 0 0)
			(layers "F.Cu" "F.Mask" "F.Paste")
			(net "SMB_PDBV_FAN_SDA")
		)
		(pad "2" smd circle
			(at 0.40005 0 180)
			(size 0 0)
			(layers "F.Cu" "F.Mask" "F.Paste")
			(net "SMB_PDBV_FAN_R_U403_SDA")
		)
	)
	(footprint ""
		(layer "F.Cu")
		(at 13.335 -170.815 180)
		(property "Reference" "R5504"
			(at 0 0 180)
			(layer "F.SilkS")
			(hide yes)
			(effects
				(font
					(size 1.27 1.27)
				)
			)
		)
		(property "Value" ""
			(at 0 0 180)
			(layer "F.Fab")
			(effects
				(font
					(size 1.27 1.27)
				)
			)
		)
		(duplicate_pad_numbers_are_jumpers no)
		(fp_line
			(start 0.7874 0.4064)
			(end -0.7874 0.4064)
			(stroke
				(width 0.1524)
				(type default)
			)
			(layer "F.SilkS")
		)
		(fp_line
			(start 0.7874 -0.4064)
			(end 0.7874 0.4064)
			(stroke
				(width 0.1524)
				(type default)
			)
			(layer "F.SilkS")
		)
		(fp_line
			(start -0.7874 0.4064)
			(end -0.7874 -0.4064)
			(stroke
				(width 0.1524)
				(type default)
			)
			(layer "F.SilkS")
		)
		(fp_line
			(start -0.7874 -0.4064)
			(end 0.7874 -0.4064)
			(stroke
				(width 0.1524)
				(type default)
			)
			(layer "F.SilkS")
		)
		(fp_line
			(start 0.67945 0.3048)
			(end 0.120396 0.3048)
			(stroke
				(width 0.1)
				(type default)
			)
			(layer "F.Fab")
		)
		(fp_line
			(start 0.67945 -0.3048)
			(end 0.67945 0.3048)
			(stroke
				(width 0.1)
				(type default)
			)
			(layer "F.Fab")
		)
		(fp_line
			(start 0.12065 -0.2794)
			(end 0.12065 -0.3048)
			(stroke
				(width 0.1)
				(type default)
			)
			(layer "F.Fab")
		)
		(fp_line
			(start 0.12065 -0.3048)
			(end 0.67945 -0.3048)
			(stroke
				(width 0.1)
				(type default)
			)
			(layer "F.Fab")
		)
		(fp_line
			(start 0.120396 0.3048)
			(end 0.120396 0.2794)
			(stroke
				(width 0.1)
				(type default)
			)
			(layer "F.Fab")
		)
		(fp_line
			(start 0.120396 0.2794)
			(end -0.12065 0.2794)
			(stroke
				(width 0.1)
				(type default)
			)
			(layer "F.Fab")
		)
		(fp_line
			(start -0.12065 0.3048)
			(end -0.67945 0.3048)
			(stroke
				(width 0.1)
				(type default)
			)
			(layer "F.Fab")
		)
		(fp_line
			(start -0.12065 0.2794)
			(end -0.12065 0.3048)
			(stroke
				(width 0.1)
				(type default)
			)
			(layer "F.Fab")
		)
		(fp_line
			(start -0.12065 -0.2794)
			(end 0.12065 -0.2794)
			(stroke
				(width 0.1)
				(type default)
			)
			(layer "F.Fab")
		)
		(fp_line
			(start -0.12065 -0.305054)
			(end -0.12065 -0.2794)
			(stroke
				(width 0.1)
				(type default)
			)
			(layer "F.Fab")
		)
		(fp_line
			(start -0.67945 0.3048)
			(end -0.67945 -0.305054)
			(stroke
				(width 0.1)
				(type default)
			)
			(layer "F.Fab")
		)
		(fp_line
			(start -0.67945 -0.305054)
			(end -0.12065 -0.305054)
			(stroke
				(width 0.1)
				(type default)
			)
			(layer "F.Fab")
		)
		(pad "1" smd circle
			(at -0.40005 0 180)
			(size 0 0)
			(layers "F.Cu" "F.Mask" "F.Paste")
			(net "P3V3_AUX")
		)
		(pad "2" smd circle
			(at 0.40005 0 180)
			(size 0 0)
			(layers "F.Cu" "F.Mask" "F.Paste")
			(net "FAN_5_PRESENT_N")
		)
	)
	(footprint ""
		(layer "F.Cu")
		(at 16.891 -108.458 180)
		(property "Reference" "R5538"
			(at 0 0 180)
			(layer "F.SilkS")
			(hide yes)
			(effects
				(font
					(size 1.27 1.27)
				)
			)
		)
		(property "Value" ""
			(at 0 0 180)
			(layer "F.Fab")
			(effects
				(font
					(size 1.27 1.27)
				)
			)
		)
		(duplicate_pad_numbers_are_jumpers no)
		(fp_line
			(start 0.7874 0.4064)
			(end -0.7874 0.4064)
			(stroke
				(width 0.1524)
				(type default)
			)
			(layer "F.SilkS")
		)
		(fp_line
			(start 0.7874 -0.4064)
			(end 0.7874 0.4064)
			(stroke
				(width 0.1524)
				(type default)
			)
			(layer "F.SilkS")
		)
		(fp_line
			(start -0.7874 0.4064)
			(end -0.7874 -0.4064)
			(stroke
				(width 0.1524)
				(type default)
			)
			(layer "F.SilkS")
		)
		(fp_line
			(start -0.7874 -0.4064)
			(end 0.7874 -0.4064)
			(stroke
				(width 0.1524)
				(type default)
			)
			(layer "F.SilkS")
		)
		(fp_line
			(start 0.67945 0.3048)
			(end 0.120396 0.3048)
			(stroke
				(width 0.1)
				(type default)
			)
			(layer "F.Fab")
		)
		(fp_line
			(start 0.67945 -0.3048)
			(end 0.67945 0.3048)
			(stroke
				(width 0.1)
				(type default)
			)
			(layer "F.Fab")
		)
		(fp_line
			(start 0.12065 -0.2794)
			(end 0.12065 -0.3048)
			(stroke
				(width 0.1)
				(type default)
			)
			(layer "F.Fab")
		)
		(fp_line
			(start 0.12065 -0.3048)
			(end 0.67945 -0.3048)
			(stroke
				(width 0.1)
				(type default)
			)
			(layer "F.Fab")
		)
		(fp_line
			(start 0.120396 0.3048)
			(end 0.120396 0.2794)
			(stroke
				(width 0.1)
				(type default)
			)
			(layer "F.Fab")
		)
		(fp_line
			(start 0.120396 0.2794)
			(end -0.12065 0.2794)
			(stroke
				(width 0.1)
				(type default)
			)
			(layer "F.Fab")
		)
		(fp_line
			(start -0.12065 0.3048)
			(end -0.67945 0.3048)
			(stroke
				(width 0.1)
				(type default)
			)
			(layer "F.Fab")
		)
		(fp_line
			(start -0.12065 0.2794)
			(end -0.12065 0.3048)
			(stroke
				(width 0.1)
				(type default)
			)
			(layer "F.Fab")
		)
		(fp_line
			(start -0.12065 -0.2794)
			(end 0.12065 -0.2794)
			(stroke
				(width 0.1)
				(type default)
			)
			(layer "F.Fab")
		)
		(fp_line
			(start -0.12065 -0.305054)
			(end -0.12065 -0.2794)
			(stroke
				(width 0.1)
				(type default)
			)
			(layer "F.Fab")
		)
		(fp_line
			(start -0.67945 0.3048)
			(end -0.67945 -0.305054)
			(stroke
				(width 0.1)
				(type default)
			)
			(layer "F.Fab")
		)
		(fp_line
			(start -0.67945 -0.305054)
			(end -0.12065 -0.305054)
			(stroke
				(width 0.1)
				(type default)
			)
			(layer "F.Fab")
		)
		(pad "1" smd rect
			(at -0.40005 0)
			(size 0.4572 0.508)
			(layers "F.Cu" "F.Mask" "F.Paste")
			(net "P12V_LED_FAN5")
		)
		(pad "2" smd rect
			(at 0.40005 0)
			(size 0.4572 0.508)
			(layers "F.Cu" "F.Mask" "F.Paste")
			(net "FAN_5_FAIL_LED_R_N")
		)
	)
	(footprint ""
		(layer "F.Cu")
		(at 36.703 -22.098 -90)
		(property "Reference" "R5408"
			(at 0 0 270)
			(layer "F.SilkS")
			(hide yes)
			(effects
				(font
					(size 1.27 1.27)
				)
			)
		)
		(property "Value" ""
			(at 0 0 270)
			(layer "F.Fab")
			(effects
				(font
					(size 1.27 1.27)
				)
			)
		)
		(duplicate_pad_numbers_are_jumpers no)
		(fp_line
			(start -0.7874 0.4064)
			(end -0.7874 -0.4064)
			(stroke
				(width 0.1524)
				(type default)
			)
			(layer "F.SilkS")
		)
		(fp_line
			(start 0.7874 0.4064)
			(end -0.7874 0.4064)
			(stroke
				(width 0.1524)
				(type default)
			)
			(layer "F.SilkS")
		)
		(fp_line
			(start -0.7874 -0.4064)
			(end 0.7874 -0.4064)
			(stroke
				(width 0.1524)
				(type default)
			)
			(layer "F.SilkS")
		)
		(fp_line
			(start 0.7874 -0.4064)
			(end 0.7874 0.4064)
			(stroke
				(width 0.1524)
				(type default)
			)
			(layer "F.SilkS")
		)
		(fp_line
			(start -0.67945 0.3048)
			(end -0.67945 -0.305054)
			(stroke
				(width 0.1)
				(type default)
			)
			(layer "F.Fab")
		)
		(fp_line
			(start -0.12065 0.3048)
			(end -0.67945 0.3048)
			(stroke
				(width 0.1)
				(type default)
			)
			(layer "F.Fab")
		)
		(fp_line
			(start 0.120396 0.3048)
			(end 0.120396 0.2794)
			(stroke
				(width 0.1)
				(type default)
			)
			(layer "F.Fab")
		)
		(fp_line
			(start 0.67945 0.3048)
			(end 0.120396 0.3048)
			(stroke
				(width 0.1)
				(type default)
			)
			(layer "F.Fab")
		)
		(fp_line
			(start -0.12065 0.2794)
			(end -0.12065 0.3048)
			(stroke
				(width 0.1)
				(type default)
			)
			(layer "F.Fab")
		)
		(fp_line
			(start 0.120396 0.2794)
			(end -0.12065 0.2794)
			(stroke
				(width 0.1)
				(type default)
			)
			(layer "F.Fab")
		)
		(fp_line
			(start -0.12065 -0.2794)
			(end 0.12065 -0.2794)
			(stroke
				(width 0.1)
				(type default)
			)
			(layer "F.Fab")
		)
		(fp_line
			(start 0.12065 -0.2794)
			(end 0.12065 -0.3048)
			(stroke
				(width 0.1)
				(type default)
			)
			(layer "F.Fab")
		)
		(fp_line
			(start 0.12065 -0.3048)
			(end 0.67945 -0.3048)
			(stroke
				(width 0.1)
				(type default)
			)
			(layer "F.Fab")
		)
		(fp_line
			(start 0.67945 -0.3048)
			(end 0.67945 0.3048)
			(stroke
				(width 0.1)
				(type default)
			)
			(layer "F.Fab")
		)
		(fp_line
			(start -0.67945 -0.305054)
			(end -0.12065 -0.305054)
			(stroke
				(width 0.1)
				(type default)
			)
			(layer "F.Fab")
		)
		(fp_line
			(start -0.12065 -0.305054)
			(end -0.12065 -0.2794)
			(stroke
				(width 0.1)
				(type default)
			)
			(layer "F.Fab")
		)
		(pad "1" smd rect
			(at -0.40005 0 90)
			(size 0.4572 0.508)
			(layers "F.Cu" "F.Mask" "F.Paste")
			(net "FAN_3_FAIL_LED_R_N")
		)
		(pad "2" smd rect
			(at 0.40005 0 90)
			(size 0.4572 0.508)
			(layers "F.Cu" "F.Mask" "F.Paste")
			(net "FAN_3_FAIL_R_LED_N")
		)
	)
	(footprint ""
		(layer "F.Cu")
		(at 6.477 -166.116)
		(property "Reference" "R101"
			(at 0 0 0)
			(layer "F.SilkS")
			(hide yes)
			(effects
				(font
					(size 1.27 1.27)
				)
			)
		)
		(property "Value" ""
			(at 0 0 0)
			(layer "F.Fab")
			(effects
				(font
					(size 1.27 1.27)
				)
			)
		)
		(duplicate_pad_numbers_are_jumpers no)
		(fp_line
			(start -0.7874 -0.4064)
			(end 0.7874 -0.4064)
			(stroke
				(width 0.1524)
				(type default)
			)
			(layer "F.SilkS")
		)
		(fp_line
			(start -0.7874 0.4064)
			(end -0.7874 -0.4064)
			(stroke
				(width 0.1524)
				(type default)
			)
			(layer "F.SilkS")
		)
		(fp_line
			(start 0.7874 -0.4064)
			(end 0.7874 0.4064)
			(stroke
				(width 0.1524)
				(type default)
			)
			(layer "F.SilkS")
		)
		(fp_line
			(start 0.7874 0.4064)
			(end -0.7874 0.4064)
			(stroke
				(width 0.1524)
				(type default)
			)
			(layer "F.SilkS")
		)
		(fp_line
			(start -0.67945 -0.305054)
			(end -0.12065 -0.305054)
			(stroke
				(width 0.1)
				(type default)
			)
			(layer "F.Fab")
		)
		(fp_line
			(start -0.67945 0.3048)
			(end -0.67945 -0.305054)
			(stroke
				(width 0.1)
				(type default)
			)
			(layer "F.Fab")
		)
		(fp_line
			(start -0.12065 -0.305054)
			(end -0.12065 -0.2794)
			(stroke
				(width 0.1)
				(type default)
			)
			(layer "F.Fab")
		)
		(fp_line
			(start -0.12065 -0.2794)
			(end 0.12065 -0.2794)
			(stroke
				(width 0.1)
				(type default)
			)
			(layer "F.Fab")
		)
		(fp_line
			(start -0.12065 0.2794)
			(end -0.12065 0.3048)
			(stroke
				(width 0.1)
				(type default)
			)
			(layer "F.Fab")
		)
		(fp_line
			(start -0.12065 0.3048)
			(end -0.67945 0.3048)
			(stroke
				(width 0.1)
				(type default)
			)
			(layer "F.Fab")
		)
		(fp_line
			(start 0.120396 0.2794)
			(end -0.12065 0.2794)
			(stroke
				(width 0.1)
				(type default)
			)
			(layer "F.Fab")
		)
		(fp_line
			(start 0.120396 0.3048)
			(end 0.120396 0.2794)
			(stroke
				(width 0.1)
				(type default)
			)
			(layer "F.Fab")
		)
		(fp_line
			(start 0.12065 -0.3048)
			(end 0.67945 -0.3048)
			(stroke
				(width 0.1)
				(type default)
			)
			(layer "F.Fab")
		)
		(fp_line
			(start 0.12065 -0.2794)
			(end 0.12065 -0.3048)
			(stroke
				(width 0.1)
				(type default)
			)
			(layer "F.Fab")
		)
		(fp_line
			(start 0.67945 -0.3048)
			(end 0.67945 0.3048)
			(stroke
				(width 0.1)
				(type default)
			)
			(layer "F.Fab")
		)
		(fp_line
			(start 0.67945 0.3048)
			(end 0.120396 0.3048)
			(stroke
				(width 0.1)
				(type default)
			)
			(layer "F.Fab")
		)
		(pad "1" smd circle
			(at -0.40005 0)
			(size 0 0)
			(layers "F.Cu" "F.Mask" "F.Paste")
			(net "P3V3_AUX")
		)
		(pad "2" smd circle
			(at 0.40005 0)
			(size 0 0)
			(layers "F.Cu" "F.Mask" "F.Paste")
			(net "FAN_2_PRSNT_BUF_R_N")
		)
	)
	(footprint ""
		(layer "F.Cu")
		(at 15.621 -172.466)
		(property "Reference" "C1946"
			(at 0 0 0)
			(layer "F.SilkS")
			(hide yes)
			(effects
				(font
					(size 1.27 1.27)
				)
			)
		)
		(property "Value" ""
			(at 0 0 0)
			(layer "F.Fab")
			(effects
				(font
					(size 1.27 1.27)
				)
			)
		)
		(duplicate_pad_numbers_are_jumpers no)
		(fp_line
			(start -0.7874 -0.4064)
			(end 0.7874 -0.4064)
			(stroke
				(width 0.1524)
				(type default)
			)
			(layer "F.SilkS")
		)
		(fp_line
			(start -0.7874 0.4064)
			(end -0.7874 -0.4064)
			(stroke
				(width 0.1524)
				(type default)
			)
			(layer "F.SilkS")
		)
		(fp_line
			(start 0.7874 -0.4064)
			(end 0.7874 0.4064)
			(stroke
				(width 0.1524)
				(type default)
			)
			(layer "F.SilkS")
		)
		(fp_line
			(start 0.7874 0.4064)
			(end -0.7874 0.4064)
			(stroke
				(width 0.1524)
				(type default)
			)
			(layer "F.SilkS")
		)
		(fp_line
			(start -0.67945 -0.305054)
			(end -0.12065 -0.305054)
			(stroke
				(width 0.1)
				(type default)
			)
			(layer "F.Fab")
		)
		(fp_line
			(start -0.67945 0.3048)
			(end -0.67945 -0.305054)
			(stroke
				(width 0.1)
				(type default)
			)
			(layer "F.Fab")
		)
		(fp_line
			(start -0.12065 -0.305054)
			(end -0.12065 -0.2794)
			(stroke
				(width 0.1)
				(type default)
			)
			(layer "F.Fab")
		)
		(fp_line
			(start -0.12065 -0.2794)
			(end 0.12065 -0.2794)
			(stroke
				(width 0.1)
				(type default)
			)
			(layer "F.Fab")
		)
		(fp_line
			(start -0.12065 0.2794)
			(end -0.12065 0.3048)
			(stroke
				(width 0.1)
				(type default)
			)
			(layer "F.Fab")
		)
		(fp_line
			(start -0.12065 0.3048)
			(end -0.67945 0.3048)
			(stroke
				(width 0.1)
				(type default)
			)
			(layer "F.Fab")
		)
		(fp_line
			(start 0.120396 0.2794)
			(end -0.12065 0.2794)
			(stroke
				(width 0.1)
				(type default)
			)
			(layer "F.Fab")
		)
		(fp_line
			(start 0.120396 0.3048)
			(end 0.120396 0.2794)
			(stroke
				(width 0.1)
				(type default)
			)
			(layer "F.Fab")
		)
		(fp_line
			(start 0.12065 -0.3048)
			(end 0.67945 -0.3048)
			(stroke
				(width 0.1)
				(type default)
			)
			(layer "F.Fab")
		)
		(fp_line
			(start 0.12065 -0.2794)
			(end 0.12065 -0.3048)
			(stroke
				(width 0.1)
				(type default)
			)
			(layer "F.Fab")
		)
		(fp_line
			(start 0.67945 -0.3048)
			(end 0.67945 0.3048)
			(stroke
				(width 0.1)
				(type default)
			)
			(layer "F.Fab")
		)
		(fp_line
			(start 0.67945 0.3048)
			(end 0.120396 0.3048)
			(stroke
				(width 0.1)
				(type default)
			)
			(layer "F.Fab")
		)
		(pad "1" smd circle
			(at -0.40005 0)
			(size 0 0)
			(layers "F.Cu" "F.Mask" "F.Paste")
			(net "FAN_6_PRESENT_N")
		)
		(pad "2" smd circle
			(at 0.40005 0)
			(size 0 0)
			(layers "F.Cu" "F.Mask" "F.Paste")
			(net "GND")
		)
	)
)
